FILE_TYPE = MACRO_DRAWING;
SET COLOR_WIRE YELLOW;
SET COLOR_PROP ORANGE;
SET COLOR_DOT WHITE;
SET COLOR_ARC YELLOW;
SET COLOR_BODY GREEN;
SET COLOR_NOTE PURPLE;
SET PROP_DISPLAY VALUE;
SET PAGE_NUMBER P253;
FORCEADD OFFPAGE..3
R 2
(-6675 3975);
FORCEPROP 2 LAST $XR0 251 
J 0
(-6955 3975);
DISPLAY 0.638298 (-6955 3975);
PAINT MONO (-6955 3975);
FORCEPROP 2 LAST CDS_LIB standard
J 0
(-6675 3975);
PAINT MONO (-6675 3975);
DISPLAY INVISIBLE (-6675 3975);
FORCEPROP 1 LAST OFFPAGE TRUE
J 2
(-7000 3850);
DISPLAY 0.872340 (-7000 3850);
DISPLAY INVISIBLE (-7000 3850);
FORCEPROP 1 LAST COMMENT_BODY TRUE
J 2
(-6625 3875);
DISPLAY 0.872340 (-6625 3875);
PAINT GREEN (-6625 3875);
DISPLAY INVISIBLE (-6625 3875);
FORCEPROP 2 LAST PATH I1
J 0
(-6950 4025);
DISPLAY 0.680851 (-6950 4025);
DISPLAY INVISIBLE (-6950 4025);
FORCEADD Q_RES..1
(-4950 3675);
FORCEPROP 1 LAST LOCATION R3588
J 0
(-5200 3675);
DISPLAY 0.787234 (-5200 3675);
FORCEPROP 2 LAST $SEC 1
J 0
(-5000 3875);
DISPLAY 0.680851 (-5000 3875);
PAINT MONO (-5000 3875);
DISPLAY INVISIBLE (-5000 3875);
FORCEPROP 2 LAST CDS_SEC 1
J 0
(-5000 3875);
DISPLAY 1.021277 (-5000 3875);
DISPLAY INVISIBLE (-5000 3875);
FORCEPROP 1 LASTPIN (-5050 3675) $PN 1
J 0
(-5038 3687);
DISPLAY 0.787234 (-5038 3687);
FORCEPROP 1 LASTPIN (-4850 3675) $PN 2
J 0
(-4888 3687);
DISPLAY 0.787234 (-4888 3687);
FORCEPROP 1 LAST WATTAGE 1/16W
J 2
(-4775 3800);
DISPLAY 0.510638 (-4775 3800);
FORCEPROP 1 LAST MATERIAL CHIP
J 0
(-4650 3675);
DISPLAY 0.510638 (-4650 3675);
FORCEPROP 1 LAST TOLERANCE 1%
J 0
(-4725 3675);
DISPLAY 0.510638 (-4725 3675);
FORCEPROP 1 LAST VALUE 33.2
J 2
(-4750 3675);
DISPLAY 0.510638 (-4750 3675);
FORCEPROP 1 LAST PACK_TYPE 0402LF
J 0
(-5075 3800);
DISPLAY 0.510638 (-5075 3800);
FORCEPROP 2 LAST CDS_LIB pure_quanta
J 0
(-4950 3675);
PAINT MONO (-4950 3675);
DISPLAY INVISIBLE (-4950 3675);
FORCEPROP 1 LAST PATH I10
J 0
(-5000 3825);
DISPLAY 0.978723 (-5000 3825);
PAINT WHITE (-5000 3825);
DISPLAY INVISIBLE (-5000 3825);
FORCEPROP 1 LAST PART_NUMBER CS03322FB03
J 0
(-5075 3750);
DISPLAY 0.510638 (-5075 3750);
DISPLAY INVISIBLE (-5075 3750);
FORCEADD Q_RES..1
(-4950 3975);
FORCEPROP 1 LAST LOCATION R3587
J 0
(-5200 3975);
DISPLAY 0.808511 (-5200 3975);
FORCEPROP 0 LAST $SEC 1
J 0
(-5200 4025);
DISPLAY 0.680851 (-5200 4025);
PAINT MONO (-5200 4025);
DISPLAY INVISIBLE (-5200 4025);
FORCEPROP 0 LAST CDS_SEC 1
J 0
(-5200 4025);
DISPLAY 1.021277 (-5200 4025);
DISPLAY INVISIBLE (-5200 4025);
FORCEPROP 1 LASTPIN (-5050 3975) $PN 1
J 0
(-5038 3987);
DISPLAY 0.787234 (-5038 3987);
FORCEPROP 1 LASTPIN (-4850 3975) $PN 2
J 0
(-4888 3987);
DISPLAY 0.787234 (-4888 3987);
FORCEPROP 1 LAST TOLERANCE 1%
J 0
(-4725 3975);
DISPLAY 0.510638 (-4725 3975);
FORCEPROP 1 LAST VALUE 33.2
J 2
(-4750 3975);
DISPLAY 0.510638 (-4750 3975);
FORCEPROP 1 LAST MATERIAL CHIP
J 0
(-4650 3975);
DISPLAY 0.510638 (-4650 3975);
FORCEPROP 2 LAST CDS_LIB pure_quanta
J 0
(-4950 3975);
DISPLAY INVISIBLE (-4950 3975);
FORCEPROP 1 LAST WATTAGE 1/16W
J 2
(-4750 4075);
DISPLAY 0.638298 (-4750 4075);
DISPLAY INVISIBLE (-4750 4075);
FORCEPROP 1 LAST PACK_TYPE 0402LF
J 0
(-4600 3975);
DISPLAY 0.638298 (-4600 3975);
DISPLAY INVISIBLE (-4600 3975);
FORCEPROP 1 LAST PATH I11
J 0
(-5000 4125);
DISPLAY 0.978723 (-5000 4125);
PAINT WHITE (-5000 4125);
DISPLAY INVISIBLE (-5000 4125);
FORCEPROP 1 LAST PART_NUMBER CS03322FB03
J 0
(-5075 4025);
DISPLAY 0.638298 (-5075 4025);
DISPLAY INVISIBLE (-5075 4025);
FORCEADD Q_RES..1
(-4950 4025);
FORCEPROP 1 LAST LOCATION R3586
J 0
(-5200 4025);
DISPLAY 0.808511 (-5200 4025);
FORCEPROP 0 LAST $SEC 1
J 0
(-4775 4175);
DISPLAY 0.680851 (-4775 4175);
PAINT MONO (-4775 4175);
DISPLAY INVISIBLE (-4775 4175);
FORCEPROP 0 LAST CDS_SEC 1
J 0
(-4775 4175);
DISPLAY 1.021277 (-4775 4175);
DISPLAY INVISIBLE (-4775 4175);
FORCEPROP 1 LASTPIN (-5050 4025) $PN 1
J 0
(-5038 4037);
DISPLAY 0.787234 (-5038 4037);
FORCEPROP 1 LASTPIN (-4850 4025) $PN 2
J 0
(-4888 4037);
DISPLAY 0.787234 (-4888 4037);
FORCEPROP 1 LAST WATTAGE 1/16W
J 2
(-4775 4150);
DISPLAY 0.510638 (-4775 4150);
FORCEPROP 1 LAST VALUE 33.2
J 2
(-4750 4025);
DISPLAY 0.510638 (-4750 4025);
FORCEPROP 1 LAST TOLERANCE 1%
J 0
(-4725 4025);
DISPLAY 0.510638 (-4725 4025);
FORCEPROP 1 LAST MATERIAL CHIP
J 0
(-4650 4025);
DISPLAY 0.510638 (-4650 4025);
FORCEPROP 1 LAST PACK_TYPE 0402LF
J 0
(-5075 4150);
DISPLAY 0.510638 (-5075 4150);
FORCEPROP 2 LAST CDS_LIB pure_quanta
J 0
(-4950 4025);
DISPLAY INVISIBLE (-4950 4025);
FORCEPROP 1 LAST PATH I12
J 0
(-5000 4175);
DISPLAY 0.978723 (-5000 4175);
PAINT WHITE (-5000 4175);
DISPLAY INVISIBLE (-5000 4175);
FORCEPROP 1 LAST PART_NUMBER CS03322FB03
J 0
(-5075 4100);
DISPLAY 0.510638 (-5075 4100);
DISPLAY INVISIBLE (-5075 4100);
FORCEADD OFFPAGE..2
(-3275 2825);
FORCEPROP 2 LAST $XR0 238 
J 0
(-3086 2825);
DISPLAY 0.638298 (-3086 2825);
PAINT MONO (-3086 2825);
FORCEPROP 2 LAST CDS_LIB standard
J 0
(-3275 2825);
PAINT MONO (-3275 2825);
DISPLAY INVISIBLE (-3275 2825);
FORCEPROP 1 LAST OFFPAGE TRUE
J 0
(-2950 2700);
DISPLAY 1.170213 (-2950 2700);
PAINT GREEN (-2950 2700);
DISPLAY INVISIBLE (-2950 2700);
FORCEPROP 1 LAST COMMENT_BODY TRUE
J 0
(-3320 2730);
DISPLAY 1.170213 (-3320 2730);
PAINT GREEN (-3320 2730);
DISPLAY INVISIBLE (-3320 2730);
FORCEPROP 2 LAST PATH I13
J 0
(-3075 2875);
DISPLAY 0.680851 (-3075 2875);
DISPLAY INVISIBLE (-3075 2875);
FORCEADD OFFPAGE..3
(-3275 2775);
FORCEPROP 2 LAST $XR0 238 
J 0
(-3061 2775);
DISPLAY 0.638298 (-3061 2775);
PAINT MONO (-3061 2775);
FORCEPROP 2 LAST CDS_LIB standard
J 0
(-3275 2775);
PAINT MONO (-3275 2775);
DISPLAY INVISIBLE (-3275 2775);
FORCEPROP 1 LAST OFFPAGE TRUE
J 0
(-2950 2650);
DISPLAY 0.872340 (-2950 2650);
DISPLAY INVISIBLE (-2950 2650);
FORCEPROP 1 LAST COMMENT_BODY TRUE
J 0
(-3325 2675);
DISPLAY 0.872340 (-3325 2675);
PAINT GREEN (-3325 2675);
DISPLAY INVISIBLE (-3325 2675);
FORCEPROP 2 LAST PATH I14
J 0
(-3050 2825);
DISPLAY 0.680851 (-3050 2825);
DISPLAY INVISIBLE (-3050 2825);
FORCEADD OFFPAGE..2
(-3250 3100);
FORCEPROP 2 LAST $XR0 238 
J 0
(-3061 3100);
DISPLAY 0.638298 (-3061 3100);
PAINT MONO (-3061 3100);
FORCEPROP 2 LAST CDS_LIB standard
J 0
(-3250 3100);
PAINT MONO (-3250 3100);
DISPLAY INVISIBLE (-3250 3100);
FORCEPROP 1 LAST OFFPAGE TRUE
J 0
(-2925 2975);
DISPLAY 1.170213 (-2925 2975);
PAINT GREEN (-2925 2975);
DISPLAY INVISIBLE (-2925 2975);
FORCEPROP 1 LAST COMMENT_BODY TRUE
J 0
(-3295 3005);
DISPLAY 1.170213 (-3295 3005);
PAINT GREEN (-3295 3005);
DISPLAY INVISIBLE (-3295 3005);
FORCEPROP 2 LAST PATH I15
J 0
(-3050 3150);
DISPLAY 0.680851 (-3050 3150);
DISPLAY INVISIBLE (-3050 3150);
FORCEADD OFFPAGE..3
(-3250 3050);
FORCEPROP 2 LAST $XR0 238 
J 0
(-3036 3050);
DISPLAY 0.638298 (-3036 3050);
PAINT MONO (-3036 3050);
FORCEPROP 2 LAST CDS_LIB standard
J 0
(-3250 3050);
PAINT MONO (-3250 3050);
DISPLAY INVISIBLE (-3250 3050);
FORCEPROP 1 LAST OFFPAGE TRUE
J 0
(-2925 2925);
DISPLAY 0.872340 (-2925 2925);
DISPLAY INVISIBLE (-2925 2925);
FORCEPROP 1 LAST COMMENT_BODY TRUE
J 0
(-3300 2950);
DISPLAY 0.872340 (-3300 2950);
PAINT GREEN (-3300 2950);
DISPLAY INVISIBLE (-3300 2950);
FORCEPROP 2 LAST PATH I16
J 0
(-3025 3100);
DISPLAY 0.680851 (-3025 3100);
DISPLAY INVISIBLE (-3025 3100);
FORCEADD OFFPAGE..3
(-3275 3350);
FORCEPROP 2 LAST $XR0 238 
J 0
(-3061 3350);
DISPLAY 0.638298 (-3061 3350);
PAINT MONO (-3061 3350);
FORCEPROP 2 LAST CDS_LIB standard
J 0
(-3275 3350);
PAINT MONO (-3275 3350);
DISPLAY INVISIBLE (-3275 3350);
FORCEPROP 1 LAST OFFPAGE TRUE
J 0
(-2950 3225);
DISPLAY 0.872340 (-2950 3225);
DISPLAY INVISIBLE (-2950 3225);
FORCEPROP 1 LAST COMMENT_BODY TRUE
J 0
(-3325 3250);
DISPLAY 0.872340 (-3325 3250);
PAINT GREEN (-3325 3250);
DISPLAY INVISIBLE (-3325 3250);
FORCEPROP 2 LAST PATH I17
J 0
(-3050 3400);
DISPLAY 0.680851 (-3050 3400);
DISPLAY INVISIBLE (-3050 3400);
FORCEADD OFFPAGE..2
(-3275 3400);
FORCEPROP 2 LAST $XR0 238 
J 0
(-3086 3400);
DISPLAY 0.638298 (-3086 3400);
PAINT MONO (-3086 3400);
FORCEPROP 2 LAST CDS_LIB standard
J 0
(-3275 3400);
PAINT MONO (-3275 3400);
DISPLAY INVISIBLE (-3275 3400);
FORCEPROP 1 LAST OFFPAGE TRUE
J 0
(-2950 3275);
DISPLAY 1.170213 (-2950 3275);
PAINT GREEN (-2950 3275);
DISPLAY INVISIBLE (-2950 3275);
FORCEPROP 1 LAST COMMENT_BODY TRUE
J 0
(-3320 3305);
DISPLAY 1.170213 (-3320 3305);
PAINT GREEN (-3320 3305);
DISPLAY INVISIBLE (-3320 3305);
FORCEPROP 2 LAST PATH I18
J 0
(-3075 3450);
DISPLAY 0.680851 (-3075 3450);
DISPLAY INVISIBLE (-3075 3450);
FORCEADD OFFPAGE..3
(-3275 3625);
FORCEPROP 2 LAST $XR0 237 
J 0
(-3061 3625);
DISPLAY 0.638298 (-3061 3625);
PAINT MONO (-3061 3625);
FORCEPROP 2 LAST CDS_LIB standard
J 0
(-3275 3625);
PAINT MONO (-3275 3625);
DISPLAY INVISIBLE (-3275 3625);
FORCEPROP 1 LAST OFFPAGE TRUE
J 0
(-2950 3500);
DISPLAY 0.872340 (-2950 3500);
DISPLAY INVISIBLE (-2950 3500);
FORCEPROP 1 LAST COMMENT_BODY TRUE
J 0
(-3325 3525);
DISPLAY 0.872340 (-3325 3525);
PAINT GREEN (-3325 3525);
DISPLAY INVISIBLE (-3325 3525);
FORCEPROP 2 LAST PATH I19
J 0
(-3050 3675);
DISPLAY 0.680851 (-3050 3675);
DISPLAY INVISIBLE (-3050 3675);
FORCEADD OFFPAGE..1
(-6675 4025);
FORCEPROP 2 LAST $XR0 251 
J 0
(-6927 4025);
DISPLAY 0.638298 (-6927 4025);
PAINT MONO (-6927 4025);
FORCEPROP 2 LAST CDS_LIB standard
J 0
(-6675 4025);
PAINT MONO (-6675 4025);
DISPLAY INVISIBLE (-6675 4025);
FORCEPROP 1 LAST OFFPAGE TRUE
J 0
(-6350 3900);
DISPLAY 0.872340 (-6350 3900);
PAINT GREEN (-6350 3900);
DISPLAY INVISIBLE (-6350 3900);
FORCEPROP 1 LAST COMMENT_BODY TRUE
J 0
(-6550 3925);
DISPLAY 0.872340 (-6550 3925);
PAINT GREEN (-6550 3925);
DISPLAY INVISIBLE (-6550 3925);
FORCEPROP 2 LAST PATH I2
J 0
(-6925 4075);
DISPLAY 0.680851 (-6925 4075);
DISPLAY INVISIBLE (-6925 4075);
FORCEADD OFFPAGE..2
(-3275 3675);
FORCEPROP 2 LAST $XR0 237 
J 0
(-3086 3675);
DISPLAY 0.638298 (-3086 3675);
PAINT MONO (-3086 3675);
FORCEPROP 2 LAST CDS_LIB standard
J 0
(-3275 3675);
PAINT MONO (-3275 3675);
DISPLAY INVISIBLE (-3275 3675);
FORCEPROP 1 LAST OFFPAGE TRUE
J 0
(-2950 3550);
DISPLAY 1.170213 (-2950 3550);
PAINT GREEN (-2950 3550);
DISPLAY INVISIBLE (-2950 3550);
FORCEPROP 1 LAST COMMENT_BODY TRUE
J 0
(-3320 3580);
DISPLAY 1.170213 (-3320 3580);
PAINT GREEN (-3320 3580);
DISPLAY INVISIBLE (-3320 3580);
FORCEPROP 2 LAST PATH I20
J 0
(-3075 3725);
DISPLAY 0.680851 (-3075 3725);
DISPLAY INVISIBLE (-3075 3725);
FORCEADD OFFPAGE..2
(-3275 4025);
FORCEPROP 2 LAST $XR0 237 
J 0
(-3086 4025);
DISPLAY 0.638298 (-3086 4025);
PAINT MONO (-3086 4025);
FORCEPROP 2 LAST CDS_LIB standard
J 0
(-3275 4025);
PAINT MONO (-3275 4025);
DISPLAY INVISIBLE (-3275 4025);
FORCEPROP 1 LAST OFFPAGE TRUE
J 0
(-2950 3900);
DISPLAY 1.170213 (-2950 3900);
PAINT GREEN (-2950 3900);
DISPLAY INVISIBLE (-2950 3900);
FORCEPROP 1 LAST COMMENT_BODY TRUE
J 0
(-3320 3930);
DISPLAY 1.170213 (-3320 3930);
PAINT GREEN (-3320 3930);
DISPLAY INVISIBLE (-3320 3930);
FORCEPROP 2 LAST PATH I21
J 0
(-3075 4075);
DISPLAY 0.680851 (-3075 4075);
DISPLAY INVISIBLE (-3075 4075);
FORCEADD OFFPAGE..3
(-3275 3975);
FORCEPROP 2 LAST $XR0 237 
J 0
(-3061 3975);
DISPLAY 0.638298 (-3061 3975);
PAINT MONO (-3061 3975);
FORCEPROP 2 LAST CDS_LIB standard
J 0
(-3275 3975);
PAINT MONO (-3275 3975);
DISPLAY INVISIBLE (-3275 3975);
FORCEPROP 1 LAST OFFPAGE TRUE
J 0
(-2950 3850);
DISPLAY 0.872340 (-2950 3850);
DISPLAY INVISIBLE (-2950 3850);
FORCEPROP 1 LAST COMMENT_BODY TRUE
J 0
(-3325 3875);
DISPLAY 0.872340 (-3325 3875);
PAINT GREEN (-3325 3875);
DISPLAY INVISIBLE (-3325 3875);
FORCEPROP 2 LAST PATH I22
J 0
(-3050 4025);
DISPLAY 0.680851 (-3050 4025);
DISPLAY INVISIBLE (-3050 4025);
FORCEADD Q_RES..1
(-4950 2525);
FORCEPROP 1 LAST LOCATION R1344
J 0
(-5200 2525);
DISPLAY 0.808511 (-5200 2525);
FORCEPROP 0 LAST $SEC 1
J 0
(-4775 2675);
DISPLAY 0.680851 (-4775 2675);
PAINT MONO (-4775 2675);
DISPLAY INVISIBLE (-4775 2675);
FORCEPROP 0 LAST CDS_SEC 1
J 0
(-4775 2675);
DISPLAY 0.680851 (-4775 2675);
DISPLAY INVISIBLE (-4775 2675);
FORCEPROP 1 LASTPIN (-5050 2525) $PN 1
J 0
(-5038 2537);
DISPLAY 0.787234 (-5038 2537);
PAINT MONO (-5038 2537);
FORCEPROP 1 LASTPIN (-4850 2525) $PN 2
J 0
(-4888 2537);
DISPLAY 0.787234 (-4888 2537);
PAINT MONO (-4888 2537);
FORCEPROP 1 LAST PACK_TYPE 0402LF
J 0
(-5075 2650);
DISPLAY 0.510638 (-5075 2650);
FORCEPROP 1 LAST VALUE 33.2
J 2
(-4750 2525);
DISPLAY 0.510638 (-4750 2525);
FORCEPROP 1 LAST MATERIAL CHIP
J 0
(-4650 2525);
DISPLAY 0.510638 (-4650 2525);
FORCEPROP 1 LAST WATTAGE 1/16W
J 2
(-4775 2650);
DISPLAY 0.510638 (-4775 2650);
FORCEPROP 1 LAST TOLERANCE 1%
J 0
(-4725 2525);
DISPLAY 0.510638 (-4725 2525);
FORCEPROP 2 LAST CDS_LIB pure_quanta
J 0
(-4950 2525);
DISPLAY INVISIBLE (-4950 2525);
FORCEPROP 1 LAST PATH I23
J 0
(-5000 2675);
DISPLAY 0.978723 (-5000 2675);
PAINT WHITE (-5000 2675);
DISPLAY INVISIBLE (-5000 2675);
FORCEPROP 1 LAST PART_NUMBER CS03322FB03
J 0
(-5075 2600);
DISPLAY 0.510638 (-5075 2600);
DISPLAY INVISIBLE (-5075 2600);
FORCEADD Q_RES..1
(-4950 2475);
FORCEPROP 1 LAST LOCATION R1345
J 0
(-5200 2475);
DISPLAY 0.808511 (-5200 2475);
FORCEPROP 0 LAST $SEC 1
J 0
(-5200 2525);
DISPLAY 0.680851 (-5200 2525);
PAINT MONO (-5200 2525);
DISPLAY INVISIBLE (-5200 2525);
FORCEPROP 0 LAST CDS_SEC 1
J 0
(-5200 2525);
DISPLAY 0.680851 (-5200 2525);
DISPLAY INVISIBLE (-5200 2525);
FORCEPROP 1 LASTPIN (-5050 2475) $PN 1
J 0
(-5038 2487);
DISPLAY 0.787234 (-5038 2487);
PAINT MONO (-5038 2487);
FORCEPROP 1 LASTPIN (-4850 2475) $PN 2
J 0
(-4888 2487);
DISPLAY 0.787234 (-4888 2487);
PAINT MONO (-4888 2487);
FORCEPROP 1 LAST TOLERANCE 1%
J 0
(-4725 2475);
DISPLAY 0.510638 (-4725 2475);
FORCEPROP 1 LAST MATERIAL CHIP
J 0
(-4650 2475);
DISPLAY 0.510638 (-4650 2475);
FORCEPROP 1 LAST VALUE 33.2
J 2
(-4750 2475);
DISPLAY 0.510638 (-4750 2475);
FORCEPROP 1 LAST PACK_TYPE 0402LF
J 0
(-4600 2475);
DISPLAY 0.638298 (-4600 2475);
DISPLAY INVISIBLE (-4600 2475);
FORCEPROP 1 LAST WATTAGE 1/16W
J 2
(-4750 2575);
DISPLAY 0.638298 (-4750 2575);
DISPLAY INVISIBLE (-4750 2575);
FORCEPROP 2 LAST CDS_LIB pure_quanta
J 0
(-4950 2475);
DISPLAY INVISIBLE (-4950 2475);
FORCEPROP 1 LAST PATH I24
J 0
(-5000 2625);
DISPLAY 0.978723 (-5000 2625);
PAINT WHITE (-5000 2625);
DISPLAY INVISIBLE (-5000 2625);
FORCEPROP 1 LAST PART_NUMBER CS03322FB03
J 0
(-5075 2525);
DISPLAY 0.638298 (-5075 2525);
DISPLAY INVISIBLE (-5075 2525);
FORCEADD Q_RES..1
(-4950 2225);
FORCEPROP 1 LAST LOCATION R1346
J 0
(-5200 2225);
DISPLAY 0.808511 (-5200 2225);
FORCEPROP 0 LAST $SEC 1
J 0
(-4775 2375);
DISPLAY 0.680851 (-4775 2375);
PAINT MONO (-4775 2375);
DISPLAY INVISIBLE (-4775 2375);
FORCEPROP 0 LAST CDS_SEC 1
J 0
(-4775 2375);
DISPLAY 0.680851 (-4775 2375);
DISPLAY INVISIBLE (-4775 2375);
FORCEPROP 1 LASTPIN (-5050 2225) $PN 1
J 0
(-5038 2237);
DISPLAY 0.787234 (-5038 2237);
PAINT MONO (-5038 2237);
FORCEPROP 1 LASTPIN (-4850 2225) $PN 2
J 0
(-4888 2237);
DISPLAY 0.787234 (-4888 2237);
PAINT MONO (-4888 2237);
FORCEPROP 1 LAST MATERIAL CHIP
J 0
(-4650 2225);
DISPLAY 0.510638 (-4650 2225);
FORCEPROP 1 LAST WATTAGE 1/16W
J 2
(-4775 2350);
DISPLAY 0.510638 (-4775 2350);
FORCEPROP 1 LAST TOLERANCE 1%
J 0
(-4725 2225);
DISPLAY 0.510638 (-4725 2225);
FORCEPROP 1 LAST VALUE 33.2
J 2
(-4750 2225);
DISPLAY 0.510638 (-4750 2225);
FORCEPROP 1 LAST PACK_TYPE 0402LF
J 0
(-5075 2350);
DISPLAY 0.510638 (-5075 2350);
FORCEPROP 2 LAST CDS_LIB pure_quanta
J 0
(-4950 2225);
DISPLAY INVISIBLE (-4950 2225);
FORCEPROP 1 LAST PATH I25
J 0
(-5000 2375);
DISPLAY 0.978723 (-5000 2375);
PAINT WHITE (-5000 2375);
DISPLAY INVISIBLE (-5000 2375);
FORCEPROP 1 LAST PART_NUMBER CS03322FB03
J 0
(-5075 2300);
DISPLAY 0.510638 (-5075 2300);
DISPLAY INVISIBLE (-5075 2300);
FORCEADD Q_RES..1
(-4950 2175);
FORCEPROP 1 LAST LOCATION R1347
J 0
(-5200 2175);
DISPLAY 0.808511 (-5200 2175);
FORCEPROP 0 LAST $SEC 1
J 0
(-5200 2225);
DISPLAY 0.680851 (-5200 2225);
PAINT MONO (-5200 2225);
DISPLAY INVISIBLE (-5200 2225);
FORCEPROP 0 LAST CDS_SEC 1
J 0
(-5200 2225);
DISPLAY 0.680851 (-5200 2225);
DISPLAY INVISIBLE (-5200 2225);
FORCEPROP 1 LASTPIN (-5050 2175) $PN 1
J 0
(-5038 2187);
DISPLAY 0.787234 (-5038 2187);
PAINT MONO (-5038 2187);
FORCEPROP 1 LASTPIN (-4850 2175) $PN 2
J 0
(-4888 2187);
DISPLAY 0.787234 (-4888 2187);
PAINT MONO (-4888 2187);
FORCEPROP 1 LAST MATERIAL CHIP
J 0
(-4650 2175);
DISPLAY 0.510638 (-4650 2175);
FORCEPROP 1 LAST TOLERANCE 1%
J 0
(-4725 2175);
DISPLAY 0.510638 (-4725 2175);
FORCEPROP 1 LAST VALUE 33.2
J 2
(-4750 2175);
DISPLAY 0.510638 (-4750 2175);
FORCEPROP 1 LAST PACK_TYPE 0402LF
J 0
(-4600 2175);
DISPLAY 0.638298 (-4600 2175);
DISPLAY INVISIBLE (-4600 2175);
FORCEPROP 1 LAST WATTAGE 1/16W
J 2
(-4750 2275);
DISPLAY 0.638298 (-4750 2275);
DISPLAY INVISIBLE (-4750 2275);
FORCEPROP 2 LAST CDS_LIB pure_quanta
J 0
(-4950 2175);
DISPLAY INVISIBLE (-4950 2175);
FORCEPROP 1 LAST PATH I26
J 0
(-5000 2325);
DISPLAY 0.978723 (-5000 2325);
PAINT WHITE (-5000 2325);
DISPLAY INVISIBLE (-5000 2325);
FORCEPROP 1 LAST PART_NUMBER CS03322FB03
J 0
(-5075 2225);
DISPLAY 0.638298 (-5075 2225);
DISPLAY INVISIBLE (-5075 2225);
FORCEADD Q_RES..1
(-4950 1875);
FORCEPROP 1 LAST LOCATION R1348
J 0
(-5200 1875);
DISPLAY 0.808511 (-5200 1875);
FORCEPROP 0 LAST $SEC 1
J 0
(-4775 2025);
DISPLAY 0.680851 (-4775 2025);
PAINT MONO (-4775 2025);
DISPLAY INVISIBLE (-4775 2025);
FORCEPROP 0 LAST CDS_SEC 1
J 0
(-4775 2025);
DISPLAY 0.680851 (-4775 2025);
DISPLAY INVISIBLE (-4775 2025);
FORCEPROP 1 LASTPIN (-5050 1875) $PN 1
J 0
(-5038 1887);
DISPLAY 0.787234 (-5038 1887);
PAINT MONO (-5038 1887);
FORCEPROP 1 LASTPIN (-4850 1875) $PN 2
J 0
(-4888 1887);
DISPLAY 0.787234 (-4888 1887);
PAINT MONO (-4888 1887);
FORCEPROP 1 LAST WATTAGE 1/16W
J 2
(-4775 2000);
DISPLAY 0.510638 (-4775 2000);
FORCEPROP 1 LAST PACK_TYPE 0402LF
J 0
(-5075 2000);
DISPLAY 0.510638 (-5075 2000);
FORCEPROP 1 LAST TOLERANCE 1%
J 0
(-4725 1875);
DISPLAY 0.510638 (-4725 1875);
FORCEPROP 1 LAST VALUE 33.2
J 2
(-4750 1875);
DISPLAY 0.510638 (-4750 1875);
FORCEPROP 1 LAST MATERIAL CHIP
J 0
(-4650 1875);
DISPLAY 0.510638 (-4650 1875);
FORCEPROP 2 LAST CDS_LIB pure_quanta
J 0
(-4950 1875);
DISPLAY INVISIBLE (-4950 1875);
FORCEPROP 1 LAST PATH I27
J 0
(-5000 2025);
DISPLAY 0.978723 (-5000 2025);
PAINT WHITE (-5000 2025);
DISPLAY INVISIBLE (-5000 2025);
FORCEPROP 1 LAST PART_NUMBER CS03322FB03
J 0
(-5075 1950);
DISPLAY 0.510638 (-5075 1950);
DISPLAY INVISIBLE (-5075 1950);
FORCEADD Q_RES..1
(-4950 1825);
FORCEPROP 1 LAST LOCATION R1349
J 0
(-5200 1825);
DISPLAY 0.808511 (-5200 1825);
FORCEPROP 0 LAST $SEC 1
J 0
(-5200 1875);
DISPLAY 0.680851 (-5200 1875);
PAINT MONO (-5200 1875);
DISPLAY INVISIBLE (-5200 1875);
FORCEPROP 0 LAST CDS_SEC 1
J 0
(-5200 1875);
DISPLAY 0.680851 (-5200 1875);
DISPLAY INVISIBLE (-5200 1875);
FORCEPROP 1 LASTPIN (-5050 1825) $PN 1
J 0
(-5038 1837);
DISPLAY 0.787234 (-5038 1837);
PAINT MONO (-5038 1837);
FORCEPROP 1 LASTPIN (-4850 1825) $PN 2
J 0
(-4888 1837);
DISPLAY 0.787234 (-4888 1837);
PAINT MONO (-4888 1837);
FORCEPROP 1 LAST VALUE 33.2
J 2
(-4750 1825);
DISPLAY 0.510638 (-4750 1825);
FORCEPROP 1 LAST MATERIAL CHIP
J 0
(-4650 1825);
DISPLAY 0.510638 (-4650 1825);
FORCEPROP 1 LAST TOLERANCE 1%
J 0
(-4725 1825);
DISPLAY 0.510638 (-4725 1825);
FORCEPROP 1 LAST PACK_TYPE 0402LF
J 0
(-4600 1825);
DISPLAY 0.638298 (-4600 1825);
DISPLAY INVISIBLE (-4600 1825);
FORCEPROP 1 LAST WATTAGE 1/16W
J 2
(-4750 1925);
DISPLAY 0.638298 (-4750 1925);
DISPLAY INVISIBLE (-4750 1925);
FORCEPROP 2 LAST CDS_LIB pure_quanta
J 0
(-4950 1825);
DISPLAY INVISIBLE (-4950 1825);
FORCEPROP 1 LAST PATH I28
J 0
(-5000 1975);
DISPLAY 0.978723 (-5000 1975);
PAINT WHITE (-5000 1975);
DISPLAY INVISIBLE (-5000 1975);
FORCEPROP 1 LAST PART_NUMBER CS03322FB03
J 0
(-5075 1875);
DISPLAY 0.638298 (-5075 1875);
DISPLAY INVISIBLE (-5075 1875);
FORCEADD OFFPAGE..2
(-3225 2525);
FORCEPROP 2 LAST $XR0 358 
J 0
(-3036 2525);
DISPLAY 0.638298 (-3036 2525);
PAINT MONO (-3036 2525);
FORCEPROP 2 LAST CDS_LIB standard
J 0
(-3225 2525);
DISPLAY INVISIBLE (-3225 2525);
FORCEPROP 1 LAST OFFPAGE TRUE
J 0
(-2900 2400);
DISPLAY 1.170213 (-2900 2400);
PAINT GREEN (-2900 2400);
DISPLAY INVISIBLE (-2900 2400);
FORCEPROP 1 LAST COMMENT_BODY TRUE
J 0
(-3270 2430);
DISPLAY 1.170213 (-3270 2430);
PAINT GREEN (-3270 2430);
DISPLAY INVISIBLE (-3270 2430);
FORCEPROP 2 LAST PATH I29
J 0
(-3050 2600);
DISPLAY 0.680851 (-3050 2600);
DISPLAY INVISIBLE (-3050 2600);
FORCEADD Q_RES..1
(-4950 2775);
FORCEPROP 1 LAST LOCATION R3593
J 0
(-5200 2775);
DISPLAY 0.808511 (-5200 2775);
FORCEPROP 0 LAST $SEC 1
J 0
(-5200 2825);
DISPLAY 0.680851 (-5200 2825);
PAINT MONO (-5200 2825);
DISPLAY INVISIBLE (-5200 2825);
FORCEPROP 0 LAST CDS_SEC 1
J 0
(-5200 2825);
DISPLAY 1.021277 (-5200 2825);
DISPLAY INVISIBLE (-5200 2825);
FORCEPROP 1 LASTPIN (-5050 2775) $PN 1
J 0
(-5038 2787);
DISPLAY 0.787234 (-5038 2787);
FORCEPROP 1 LASTPIN (-4850 2775) $PN 2
J 0
(-4888 2787);
DISPLAY 0.787234 (-4888 2787);
FORCEPROP 1 LAST TOLERANCE 1%
J 0
(-4725 2775);
DISPLAY 0.510638 (-4725 2775);
FORCEPROP 1 LAST MATERIAL CHIP
J 0
(-4650 2775);
DISPLAY 0.510638 (-4650 2775);
FORCEPROP 1 LAST VALUE 33.2
J 2
(-4750 2775);
DISPLAY 0.510638 (-4750 2775);
FORCEPROP 1 LAST PACK_TYPE 0402LF
J 0
(-4600 2775);
DISPLAY 0.638298 (-4600 2775);
DISPLAY INVISIBLE (-4600 2775);
FORCEPROP 1 LAST WATTAGE 1/16W
J 2
(-4750 2875);
DISPLAY 0.638298 (-4750 2875);
DISPLAY INVISIBLE (-4750 2875);
FORCEPROP 2 LAST CDS_LIB pure_quanta
J 0
(-4950 2775);
DISPLAY INVISIBLE (-4950 2775);
FORCEPROP 1 LAST PATH I3
J 0
(-5000 2925);
DISPLAY 0.978723 (-5000 2925);
PAINT WHITE (-5000 2925);
DISPLAY INVISIBLE (-5000 2925);
FORCEPROP 1 LAST PART_NUMBER CS03322FB03
J 0
(-5075 2825);
DISPLAY 0.638298 (-5075 2825);
DISPLAY INVISIBLE (-5075 2825);
FORCEADD OFFPAGE..3
(-3250 2475);
FORCEPROP 2 LAST $XR0 358 
J 0
(-3036 2475);
DISPLAY 0.638298 (-3036 2475);
PAINT MONO (-3036 2475);
FORCEPROP 2 LAST CDS_LIB standard
J 0
(-3250 2475);
DISPLAY INVISIBLE (-3250 2475);
FORCEPROP 1 LAST OFFPAGE TRUE
J 0
(-2925 2350);
DISPLAY 0.872340 (-2925 2350);
DISPLAY INVISIBLE (-2925 2350);
FORCEPROP 1 LAST COMMENT_BODY TRUE
J 0
(-3300 2375);
DISPLAY 0.872340 (-3300 2375);
PAINT GREEN (-3300 2375);
DISPLAY INVISIBLE (-3300 2375);
FORCEPROP 2 LAST PATH I30
J 0
(-3050 2550);
DISPLAY 0.680851 (-3050 2550);
DISPLAY INVISIBLE (-3050 2550);
FORCEADD OFFPAGE..3
(-3250 2175);
FORCEPROP 2 LAST $XR0 358 
J 0
(-3036 2175);
DISPLAY 0.638298 (-3036 2175);
PAINT MONO (-3036 2175);
FORCEPROP 2 LAST CDS_LIB standard
J 0
(-3250 2175);
DISPLAY INVISIBLE (-3250 2175);
FORCEPROP 1 LAST OFFPAGE TRUE
J 0
(-2925 2050);
DISPLAY 0.872340 (-2925 2050);
DISPLAY INVISIBLE (-2925 2050);
FORCEPROP 1 LAST COMMENT_BODY TRUE
J 0
(-3300 2075);
DISPLAY 0.872340 (-3300 2075);
PAINT GREEN (-3300 2075);
DISPLAY INVISIBLE (-3300 2075);
FORCEPROP 2 LAST PATH I31
J 0
(-3050 2250);
DISPLAY 0.680851 (-3050 2250);
DISPLAY INVISIBLE (-3050 2250);
FORCEADD OFFPAGE..2
(-3225 2225);
FORCEPROP 2 LAST $XR0 358 
J 0
(-3036 2225);
DISPLAY 0.638298 (-3036 2225);
PAINT MONO (-3036 2225);
FORCEPROP 2 LAST CDS_LIB standard
J 0
(-3225 2225);
DISPLAY INVISIBLE (-3225 2225);
FORCEPROP 1 LAST OFFPAGE TRUE
J 0
(-2900 2100);
DISPLAY 1.170213 (-2900 2100);
PAINT GREEN (-2900 2100);
DISPLAY INVISIBLE (-2900 2100);
FORCEPROP 1 LAST COMMENT_BODY TRUE
J 0
(-3270 2130);
DISPLAY 1.170213 (-3270 2130);
PAINT GREEN (-3270 2130);
DISPLAY INVISIBLE (-3270 2130);
FORCEPROP 2 LAST PATH I32
J 0
(-3050 2300);
DISPLAY 0.680851 (-3050 2300);
DISPLAY INVISIBLE (-3050 2300);
FORCEADD OFFPAGE..3
(-3225 1825);
FORCEPROP 2 LAST $XR0 358 
J 0
(-3011 1825);
DISPLAY 0.638298 (-3011 1825);
PAINT MONO (-3011 1825);
FORCEPROP 2 LAST CDS_LIB standard
J 0
(-3225 1825);
DISPLAY INVISIBLE (-3225 1825);
FORCEPROP 1 LAST OFFPAGE TRUE
J 0
(-2900 1700);
DISPLAY 0.872340 (-2900 1700);
DISPLAY INVISIBLE (-2900 1700);
FORCEPROP 1 LAST COMMENT_BODY TRUE
J 0
(-3275 1725);
DISPLAY 0.872340 (-3275 1725);
PAINT GREEN (-3275 1725);
DISPLAY INVISIBLE (-3275 1725);
FORCEPROP 2 LAST PATH I33
J 0
(-3025 1900);
DISPLAY 0.680851 (-3025 1900);
DISPLAY INVISIBLE (-3025 1900);
FORCEADD OFFPAGE..2
(-3200 1875);
FORCEPROP 2 LAST $XR0 358 
J 0
(-3011 1875);
DISPLAY 0.638298 (-3011 1875);
PAINT MONO (-3011 1875);
FORCEPROP 2 LAST CDS_LIB standard
J 0
(-3200 1875);
DISPLAY INVISIBLE (-3200 1875);
FORCEPROP 1 LAST OFFPAGE TRUE
J 0
(-2875 1750);
DISPLAY 1.170213 (-2875 1750);
PAINT GREEN (-2875 1750);
DISPLAY INVISIBLE (-2875 1750);
FORCEPROP 1 LAST COMMENT_BODY TRUE
J 0
(-3245 1780);
DISPLAY 1.170213 (-3245 1780);
PAINT GREEN (-3245 1780);
DISPLAY INVISIBLE (-3245 1780);
FORCEPROP 2 LAST PATH I34
J 0
(-3025 1950);
DISPLAY 0.680851 (-3025 1950);
DISPLAY INVISIBLE (-3025 1950);
FORCEADD Q_RES..1
(-4950 2825);
FORCEPROP 1 LAST LOCATION R3592
J 0
(-5200 2825);
DISPLAY 0.808511 (-5200 2825);
FORCEPROP 0 LAST $SEC 1
J 0
(-4775 2975);
DISPLAY 0.680851 (-4775 2975);
PAINT MONO (-4775 2975);
DISPLAY INVISIBLE (-4775 2975);
FORCEPROP 0 LAST CDS_SEC 1
J 0
(-4775 2975);
DISPLAY 1.021277 (-4775 2975);
DISPLAY INVISIBLE (-4775 2975);
FORCEPROP 1 LASTPIN (-5050 2825) $PN 1
J 0
(-5038 2837);
DISPLAY 0.787234 (-5038 2837);
FORCEPROP 1 LASTPIN (-4850 2825) $PN 2
J 0
(-4888 2837);
DISPLAY 0.787234 (-4888 2837);
FORCEPROP 1 LAST WATTAGE 1/16W
J 2
(-4775 2950);
DISPLAY 0.510638 (-4775 2950);
FORCEPROP 1 LAST VALUE 33.2
J 2
(-4750 2825);
DISPLAY 0.510638 (-4750 2825);
FORCEPROP 1 LAST TOLERANCE 1%
J 0
(-4725 2825);
DISPLAY 0.510638 (-4725 2825);
FORCEPROP 1 LAST MATERIAL CHIP
J 0
(-4650 2825);
DISPLAY 0.510638 (-4650 2825);
FORCEPROP 1 LAST PACK_TYPE 0402LF
J 0
(-5075 2950);
DISPLAY 0.510638 (-5075 2950);
FORCEPROP 2 LAST CDS_LIB pure_quanta
J 0
(-4950 2825);
DISPLAY INVISIBLE (-4950 2825);
FORCEPROP 1 LAST PATH I4
J 0
(-5000 2975);
DISPLAY 0.978723 (-5000 2975);
PAINT WHITE (-5000 2975);
DISPLAY INVISIBLE (-5000 2975);
FORCEPROP 1 LAST PART_NUMBER CS03322FB03
J 0
(-5075 2900);
DISPLAY 0.510638 (-5075 2900);
DISPLAY INVISIBLE (-5075 2900);
FORCEADD Q_RES..1
(-4925 3050);
FORCEPROP 1 LAST LOCATION R3595
J 0
(-5175 3050);
DISPLAY 0.787234 (-5175 3050);
FORCEPROP 2 LAST $SEC 1
J 0
(-4975 3250);
DISPLAY 0.680851 (-4975 3250);
PAINT MONO (-4975 3250);
DISPLAY INVISIBLE (-4975 3250);
FORCEPROP 2 LAST CDS_SEC 1
J 0
(-4975 3250);
DISPLAY 1.021277 (-4975 3250);
DISPLAY INVISIBLE (-4975 3250);
FORCEPROP 1 LASTPIN (-5025 3050) $PN 1
J 0
(-5013 3062);
DISPLAY 0.787234 (-5013 3062);
FORCEPROP 1 LASTPIN (-4825 3050) $PN 2
J 0
(-4863 3062);
DISPLAY 0.787234 (-4863 3062);
FORCEPROP 1 LAST MATERIAL CHIP
J 0
(-4625 3050);
DISPLAY 0.510638 (-4625 3050);
FORCEPROP 1 LAST TOLERANCE 1%
J 0
(-4700 3050);
DISPLAY 0.510638 (-4700 3050);
FORCEPROP 1 LAST VALUE 33.2
J 2
(-4725 3050);
DISPLAY 0.510638 (-4725 3050);
FORCEPROP 1 LAST WATTAGE 1/16W
J 2
(-4725 3150);
DISPLAY 0.638298 (-4725 3150);
DISPLAY INVISIBLE (-4725 3150);
FORCEPROP 1 LAST PACK_TYPE 0402LF
J 0
(-4575 3050);
DISPLAY 0.638298 (-4575 3050);
DISPLAY INVISIBLE (-4575 3050);
FORCEPROP 2 LAST CDS_LIB pure_quanta
J 0
(-4925 3050);
PAINT MONO (-4925 3050);
DISPLAY INVISIBLE (-4925 3050);
FORCEPROP 1 LAST PATH I5
J 0
(-4975 3200);
DISPLAY 0.978723 (-4975 3200);
PAINT WHITE (-4975 3200);
DISPLAY INVISIBLE (-4975 3200);
FORCEPROP 1 LAST PART_NUMBER CS03322FB03
J 0
(-5050 3100);
DISPLAY 0.638298 (-5050 3100);
DISPLAY INVISIBLE (-5050 3100);
FORCEADD Q_RES..1
(-4925 3100);
FORCEPROP 1 LAST LOCATION R3594
J 0
(-5175 3100);
DISPLAY 0.787234 (-5175 3100);
FORCEPROP 2 LAST $SEC 1
J 0
(-4975 3300);
DISPLAY 0.680851 (-4975 3300);
PAINT MONO (-4975 3300);
DISPLAY INVISIBLE (-4975 3300);
FORCEPROP 2 LAST CDS_SEC 1
J 0
(-4975 3300);
DISPLAY 1.021277 (-4975 3300);
DISPLAY INVISIBLE (-4975 3300);
FORCEPROP 1 LASTPIN (-5025 3100) $PN 1
J 0
(-5013 3112);
DISPLAY 0.787234 (-5013 3112);
FORCEPROP 1 LASTPIN (-4825 3100) $PN 2
J 0
(-4863 3112);
DISPLAY 0.787234 (-4863 3112);
FORCEPROP 1 LAST TOLERANCE 1%
J 0
(-4700 3100);
DISPLAY 0.510638 (-4700 3100);
FORCEPROP 1 LAST MATERIAL CHIP
J 0
(-4625 3100);
DISPLAY 0.510638 (-4625 3100);
FORCEPROP 1 LAST PACK_TYPE 0402LF
J 0
(-5050 3225);
DISPLAY 0.510638 (-5050 3225);
FORCEPROP 1 LAST VALUE 33.2
J 2
(-4725 3100);
DISPLAY 0.510638 (-4725 3100);
FORCEPROP 1 LAST WATTAGE 1/16W
J 2
(-4750 3225);
DISPLAY 0.510638 (-4750 3225);
FORCEPROP 2 LAST CDS_LIB pure_quanta
J 0
(-4925 3100);
PAINT MONO (-4925 3100);
DISPLAY INVISIBLE (-4925 3100);
FORCEPROP 1 LAST PATH I6
J 0
(-4975 3250);
DISPLAY 0.978723 (-4975 3250);
PAINT WHITE (-4975 3250);
DISPLAY INVISIBLE (-4975 3250);
FORCEPROP 1 LAST PART_NUMBER CS03322FB03
J 0
(-5050 3175);
DISPLAY 0.510638 (-5050 3175);
DISPLAY INVISIBLE (-5050 3175);
FORCEADD Q_RES..1
(-4950 3350);
FORCEPROP 1 LAST LOCATION R3591
J 0
(-5200 3350);
DISPLAY 0.808511 (-5200 3350);
FORCEPROP 0 LAST $SEC 1
J 0
(-5200 3400);
DISPLAY 0.680851 (-5200 3400);
PAINT MONO (-5200 3400);
DISPLAY INVISIBLE (-5200 3400);
FORCEPROP 0 LAST CDS_SEC 1
J 0
(-5200 3400);
DISPLAY 1.021277 (-5200 3400);
DISPLAY INVISIBLE (-5200 3400);
FORCEPROP 1 LASTPIN (-5050 3350) $PN 1
J 0
(-5038 3362);
DISPLAY 0.787234 (-5038 3362);
FORCEPROP 1 LASTPIN (-4850 3350) $PN 2
J 0
(-4888 3362);
DISPLAY 0.787234 (-4888 3362);
FORCEPROP 1 LAST MATERIAL CHIP
J 0
(-4650 3350);
DISPLAY 0.510638 (-4650 3350);
FORCEPROP 1 LAST TOLERANCE 1%
J 0
(-4725 3350);
DISPLAY 0.510638 (-4725 3350);
FORCEPROP 1 LAST VALUE 33.2
J 2
(-4750 3350);
DISPLAY 0.510638 (-4750 3350);
FORCEPROP 2 LAST CDS_LIB pure_quanta
J 0
(-4950 3350);
DISPLAY INVISIBLE (-4950 3350);
FORCEPROP 1 LAST WATTAGE 1/16W
J 2
(-4750 3450);
DISPLAY 0.638298 (-4750 3450);
DISPLAY INVISIBLE (-4750 3450);
FORCEPROP 1 LAST PACK_TYPE 0402LF
J 0
(-4600 3350);
DISPLAY 0.638298 (-4600 3350);
DISPLAY INVISIBLE (-4600 3350);
FORCEPROP 1 LAST PATH I7
J 0
(-5000 3500);
DISPLAY 0.978723 (-5000 3500);
PAINT WHITE (-5000 3500);
DISPLAY INVISIBLE (-5000 3500);
FORCEPROP 1 LAST PART_NUMBER CS03322FB03
J 0
(-5075 3400);
DISPLAY 0.638298 (-5075 3400);
DISPLAY INVISIBLE (-5075 3400);
FORCEADD Q_RES..1
(-4950 3400);
FORCEPROP 1 LAST LOCATION R3590
J 0
(-5200 3400);
DISPLAY 0.808511 (-5200 3400);
FORCEPROP 0 LAST $SEC 1
J 0
(-4775 3550);
DISPLAY 0.680851 (-4775 3550);
PAINT MONO (-4775 3550);
DISPLAY INVISIBLE (-4775 3550);
FORCEPROP 0 LAST CDS_SEC 1
J 0
(-4775 3550);
DISPLAY 1.021277 (-4775 3550);
DISPLAY INVISIBLE (-4775 3550);
FORCEPROP 1 LASTPIN (-5050 3400) $PN 1
J 0
(-5038 3412);
DISPLAY 0.787234 (-5038 3412);
FORCEPROP 1 LASTPIN (-4850 3400) $PN 2
J 0
(-4888 3412);
DISPLAY 0.787234 (-4888 3412);
FORCEPROP 1 LAST WATTAGE 1/16W
J 2
(-4775 3525);
DISPLAY 0.510638 (-4775 3525);
FORCEPROP 1 LAST PACK_TYPE 0402LF
J 0
(-5075 3525);
DISPLAY 0.510638 (-5075 3525);
FORCEPROP 1 LAST VALUE 33.2
J 2
(-4750 3400);
DISPLAY 0.510638 (-4750 3400);
FORCEPROP 1 LAST TOLERANCE 1%
J 0
(-4725 3400);
DISPLAY 0.510638 (-4725 3400);
FORCEPROP 1 LAST MATERIAL CHIP
J 0
(-4650 3400);
DISPLAY 0.510638 (-4650 3400);
FORCEPROP 2 LAST CDS_LIB pure_quanta
J 0
(-4950 3400);
DISPLAY INVISIBLE (-4950 3400);
FORCEPROP 1 LAST PATH I8
J 0
(-5000 3550);
DISPLAY 0.978723 (-5000 3550);
PAINT WHITE (-5000 3550);
DISPLAY INVISIBLE (-5000 3550);
FORCEPROP 1 LAST PART_NUMBER CS03322FB03
J 0
(-5075 3475);
DISPLAY 0.510638 (-5075 3475);
DISPLAY INVISIBLE (-5075 3475);
FORCEADD Q_RES..1
(-4950 3625);
FORCEPROP 1 LAST LOCATION R3589
J 0
(-5200 3625);
DISPLAY 0.787234 (-5200 3625);
FORCEPROP 2 LAST $SEC 1
J 0
(-5000 3825);
DISPLAY 0.680851 (-5000 3825);
PAINT MONO (-5000 3825);
DISPLAY INVISIBLE (-5000 3825);
FORCEPROP 2 LAST CDS_SEC 1
J 0
(-5000 3825);
DISPLAY 1.021277 (-5000 3825);
DISPLAY INVISIBLE (-5000 3825);
FORCEPROP 1 LASTPIN (-5050 3625) $PN 1
J 0
(-5038 3637);
DISPLAY 0.787234 (-5038 3637);
FORCEPROP 1 LASTPIN (-4850 3625) $PN 2
J 0
(-4888 3637);
DISPLAY 0.787234 (-4888 3637);
FORCEPROP 1 LAST MATERIAL CHIP
J 0
(-4650 3625);
DISPLAY 0.510638 (-4650 3625);
FORCEPROP 1 LAST TOLERANCE 1%
J 0
(-4725 3625);
DISPLAY 0.510638 (-4725 3625);
FORCEPROP 1 LAST VALUE 33.2
J 2
(-4750 3625);
DISPLAY 0.510638 (-4750 3625);
FORCEPROP 2 LAST CDS_LIB pure_quanta
J 0
(-4950 3625);
PAINT MONO (-4950 3625);
DISPLAY INVISIBLE (-4950 3625);
FORCEPROP 1 LAST PACK_TYPE 0402LF
J 0
(-4600 3625);
DISPLAY 0.638298 (-4600 3625);
DISPLAY INVISIBLE (-4600 3625);
FORCEPROP 1 LAST WATTAGE 1/16W
J 2
(-4750 3725);
DISPLAY 0.638298 (-4750 3725);
DISPLAY INVISIBLE (-4750 3725);
FORCEPROP 1 LAST PATH I9
J 0
(-5000 3775);
DISPLAY 0.978723 (-5000 3775);
PAINT WHITE (-5000 3775);
DISPLAY INVISIBLE (-5000 3775);
FORCEPROP 1 LAST PART_NUMBER CS03322FB03
J 0
(-5075 3675);
DISPLAY 0.638298 (-5075 3675);
DISPLAY INVISIBLE (-5075 3675);
FORCEADD QUANTA_TITLE_BLOCK_C..1
(75 100);
FORCEPROP 0 LAST CDS_CON_LAST_MODIFIED Thu Sep 14 16:12:35 2023
J 0
(-1810 115);
DISPLAY INVISIBLE (-1810 115);
FORCEPROP 1 LAST CUSTOM_TXT_CDS <CON_LAST_MODIFIED>
J 0
(-1810 115);
DISPLAY 0.978723 (-1810 115);
FORCEPROP 2 LAST CUSTOM_TXT_CDS <XR_PAGE_TITLE>
J 0
(-7815 5350);
DISPLAY 0.638298 (-7815 5350);
PAINT PINK (-7815 5350);
DISPLAY INVISIBLE (-7815 5350);
FORCEPROP 1 LAST CUSTOM_TXT_CDS <NAME_2>
J 0
(-3100 150);
FORCEPROP 1 LAST CUSTOM_TXT_CDS <NAME_1>
J 0
(-3100 275);
FORCEPROP 1 LAST CUSTOM_TXT_CDS <Q_NUMBER>
J 0
(-1328 203);
DISPLAY 1.212766 (-1328 203);
FORCEPROP 1 LAST CUSTOM_TXT_CDS <Q_PROJ>
J 0
(-2307 202);
DISPLAY 1.212766 (-2307 202);
FORCEPROP 1 LAST CUSTOM_TXT_CDS <Q_REV>
J 0
(-109 203);
DISPLAY 1.212766 (-109 203);
FORCEPROP 1 LAST CUSTOM_TXT_CDS <CON_PAGE_NUM> OF <CON_TOTAL_PAGES>
J 0
(-371 118);
DISPLAY 0.978723 (-371 118);
FORCEPROP 1 LAST Q_TITLE SMBUS - PCIE1  SMBUS
J 0
(-9291 126);
DISPLAY 2.446809 (-9291 126);
PAINT GREEN (-9291 126);
FORCEPROP 2 LAST PAGE_BORDER TRUE
J 0
(-7815 5350);
DISPLAY 0.638298 (-7815 5350);
PAINT PINK (-7815 5350);
DISPLAY INVISIBLE (-7815 5350);
FORCEPROP 1 LAST CDS_LMAN_SYM_OUTLINE -9475,6775,100,-125
J 0
(75 100);
DISPLAY 0.468085 (75 100);
PAINT GREEN (75 100);
DISPLAY INVISIBLE (75 100);
FORCEPROP 2 LAST CDS_LIB pure_quanta
J 0
(75 100);
DISPLAY INVISIBLE (75 100);
FORCEPROP 2 LAST CDS_XR_PAGE_TITLE CR-252 : @T6G_MB_LIB.T6G(SCH_1):PAGE252
J 0
(-7815 5350);
DISPLAY 0.638298 (-7815 5350);
PAINT PINK (-7815 5350);
DISPLAY INVISIBLE (-7815 5350);
FORCEPROP 1 LAST Q_DEPT BU9
J 1
(-3688 149);
DISPLAY 1.957447 (-3688 149);
PAINT GREEN (-3688 149);
DISPLAY INVISIBLE (-3688 149);
FORCEPROP 1 LAST COMMENT_BODY TRUE
J 0
(87 87);
DISPLAY 0.978723 (87 87);
PAINT GREEN (87 87);
DISPLAY INVISIBLE (87 87);
WIRE 16 -1 (-4850 3975)(-3325 3975);
FORCEPROP 2 LAST SIG_NAME SMB_INA230_1_3V3AUX_SDA_R
J 0
(-4335 3985);
DISPLAY 0.680851 (-4335 3985);
PAINT WHITE (-4335 3985);
WIRE 16 -1 (-4850 4025)(-3325 4025);
FORCEPROP 2 LAST SIG_NAME SMB_INA230_1_3V3AUX_SCL_R
J 0
(-4335 4035);
DISPLAY 0.680851 (-4335 4035);
PAINT WHITE (-4335 4035);
WIRE 16 -1 (-4825 3100)(-3300 3100);
FORCEPROP 2 LAST SIG_NAME SMB_INA230_4_3V3AUX_SCL_R
J 0
(-4310 3110);
DISPLAY 0.680851 (-4310 3110);
PAINT WHITE (-4310 3110);
WIRE 16 -1 (-4850 3675)(-3325 3675);
FORCEPROP 2 LAST SIG_NAME SMB_INA230_2_3V3AUX_SCL_R
J 0
(-4335 3685);
DISPLAY 0.680851 (-4335 3685);
PAINT WHITE (-4335 3685);
WIRE 16 -1 (-4850 3625)(-3325 3625);
FORCEPROP 2 LAST SIG_NAME SMB_INA230_2_3V3AUX_SDA_R
J 0
(-4335 3635);
DISPLAY 0.680851 (-4335 3635);
PAINT WHITE (-4335 3635);
WIRE 16 -1 (-4850 3400)(-3325 3400);
FORCEPROP 2 LAST SIG_NAME SMB_INA230_3_3V3AUX_SCL_R
J 0
(-4335 3410);
DISPLAY 0.680851 (-4335 3410);
PAINT WHITE (-4335 3410);
WIRE 16 -1 (-4850 3350)(-3325 3350);
FORCEPROP 2 LAST SIG_NAME SMB_INA230_3_3V3AUX_SDA_R
J 0
(-4335 3360);
DISPLAY 0.680851 (-4335 3360);
PAINT WHITE (-4335 3360);
WIRE 16 -1 (-5350 2225)(-5050 2225);
WIRE 16 -1 (-5350 2525)(-5350 2225);
WIRE 16 -1 (-5350 2225)(-5350 1875);
WIRE 16 -1 (-5350 1875)(-5050 1875);
WIRE 16 -1 (-5350 2525)(-5050 2525);
WIRE 16 -1 (-5350 2825)(-5350 2525);
WIRE 16 -1 (-5350 2825)(-5050 2825);
WIRE 16 -1 (-5350 3100)(-5350 2825);
WIRE 16 -1 (-5025 3100)(-5350 3100);
WIRE 16 -1 (-5350 3400)(-5350 3100);
WIRE 16 -1 (-5350 3400)(-5050 3400);
WIRE 16 -1 (-5350 3675)(-5350 3400);
WIRE 16 -1 (-5350 3675)(-5050 3675);
WIRE 16 -1 (-5350 4025)(-5350 3675);
WIRE 16 -1 (-5350 4025)(-5050 4025);
WIRE 16 -1 (-6625 4025)(-5350 4025);
FORCEPROP 2 LAST SIG_NAME SMB_INA230_3V3AUX_SCL
J 0
(-6485 4035);
DISPLAY 0.680851 (-6485 4035);
PAINT WHITE (-6485 4035);
WIRE 16 -1 (-4850 2825)(-3325 2825);
FORCEPROP 2 LAST SIG_NAME SMB_INA230_5_3V3AUX_SCL_R
J 0
(-4335 2835);
DISPLAY 0.680851 (-4335 2835);
PAINT WHITE (-4335 2835);
WIRE 16 -1 (-4825 3050)(-3300 3050);
FORCEPROP 2 LAST SIG_NAME SMB_INA230_4_3V3AUX_SDA_R
J 0
(-4310 3060);
DISPLAY 0.680851 (-4310 3060);
PAINT WHITE (-4310 3060);
WIRE 16 -1 (-4850 2225)(-3275 2225);
FORCEPROP 2 LAST SIG_NAME SMB_INA230_7_3V3AUX_SCL_R
J 0
(-4360 2235);
DISPLAY 0.680851 (-4360 2235);
WIRE 16 -1 (-4850 2775)(-3325 2775);
FORCEPROP 2 LAST SIG_NAME SMB_INA230_5_3V3AUX_SDA_R
J 0
(-4335 2785);
DISPLAY 0.680851 (-4335 2785);
PAINT WHITE (-4335 2785);
WIRE 16 -1 (-4850 2525)(-3275 2525);
FORCEPROP 2 LAST SIG_NAME SMB_INA230_6_3V3AUX_SCL_R
J 0
(-4360 2535);
DISPLAY 0.680851 (-4360 2535);
WIRE 16 -1 (-4850 1825)(-3275 1825);
FORCEPROP 2 LAST SIG_NAME SMB_INA230_8_3V3AUX_SDA_R
J 0
(-4360 1835);
DISPLAY 0.680851 (-4360 1835);
WIRE 16 -1 (-4850 1875)(-3250 1875);
FORCEPROP 2 LAST SIG_NAME SMB_INA230_8_3V3AUX_SCL_R
J 0
(-4335 1885);
DISPLAY 0.680851 (-4335 1885);
WIRE 16 -1 (-4850 2175)(-3300 2175);
FORCEPROP 2 LAST SIG_NAME SMB_INA230_7_3V3AUX_SDA_R
J 0
(-4360 2185);
DISPLAY 0.680851 (-4360 2185);
WIRE 16 -1 (-4850 2475)(-3300 2475);
FORCEPROP 2 LAST SIG_NAME SMB_INA230_6_3V3AUX_SDA_R
J 0
(-4360 2485);
DISPLAY 0.680851 (-4360 2485);
WIRE 16 -1 (-6625 3975)(-5400 3975);
FORCEPROP 2 LAST SIG_NAME SMB_INA230_3V3AUX_SDA
J 0
(-6485 3985);
DISPLAY 0.680851 (-6485 3985);
PAINT WHITE (-6485 3985);
WIRE 16 -1 (-5400 3975)(-5050 3975);
WIRE 16 -1 (-5400 3975)(-5400 3625);
WIRE 16 -1 (-5400 3625)(-5050 3625);
WIRE 16 -1 (-5400 3625)(-5400 3350);
WIRE 16 -1 (-5400 3350)(-5050 3350);
WIRE 16 -1 (-5400 3350)(-5400 3050);
WIRE 16 -1 (-5025 3050)(-5400 3050);
WIRE 16 -1 (-5400 2775)(-5400 3050);
WIRE 16 -1 (-5050 2775)(-5400 2775);
WIRE 16 -1 (-5400 2775)(-5400 2475);
WIRE 16 -1 (-5400 2475)(-5050 2475);
WIRE 16 -1 (-5400 2475)(-5400 2175);
WIRE 16 -1 (-5400 2175)(-5050 2175);
WIRE 16 -1 (-5400 2175)(-5400 1825);
WIRE 16 -1 (-5400 1825)(-5050 1825);
DOT 1 (-5400 2175);
DOT 1 (-5400 2475);
DOT 1 (-5350 2225);
DOT 1 (-5350 2825);
DOT 1 (-5350 3100);
DOT 1 (-5350 3675);
DOT 1 (-5350 4025);
DOT 1 (-5400 3975);
DOT 1 (-5400 3625);
DOT 1 (-5350 3400);
DOT 1 (-5400 3350);
DOT 1 (-5400 3050);
DOT 1 (-5400 2775);
DOT 1 (-5350 2525);
QUIT
